# T6G (Grand Teton) — schematic netlist excerpt (pin names and nets, part order shuffled) for the footprints in the layout excerpt that follows; sources: Cadence DE-HDL packaged netlist, KiCad conversion of 04192023_DAF0TMB3IC0_F0TG_MB_C_brd_V02_OCP.brd

R422  Q_RES  2.2K 5% CHIP  pkg 0402LF  page 28 : A = PVDD18_S5_P0 ; B = RST_CPU0_SYS_N
PR82  Q_RES  5.6 1% CHIP  pkg 0402LF  page 201 : A = SW_PVDDCR_CPU1_P0_BOOT1 ; B = SW_PVDDCR_CPU1_P0_BOOT1_R
C732  Q_CAP_DIFFBUS  DIFF BUS_0.22UF 6.3V 20% X6S  pkg C0201  page 66 : \1\ = P5E_CPU1_P1_TX_C_DN<4> ; \2\ = P5E_CPU1_P1_TX_DN<4>

(kicad_pcb
	(version 20260206)
	(generator "pcbnew")
	(generator_version "10.0")
	(general
		(thickness 1.6)
		(legacy_teardrops no)
	)
	(paper "A4")
	(title_block
		(title "04192023_DAF0TMB3IC0_F0TG_MB_C_brd_V02_OCP.brd")
		(comment 1 "Grand Teton / footprints 990-992 of 8354")
	)
	(layers
		(0 "F.Cu" signal "TOP")
		(4 "In1.Cu" signal "GND")
		(6 "In2.Cu" signal "IN1")
		(8 "In3.Cu" signal "GND1")
		(10 "In4.Cu" signal "IN2")
		(12 "In5.Cu" signal "GND2")
		(14 "In6.Cu" signal "IN3")
		(16 "In7.Cu" signal "GND3")
		(18 "In8.Cu" signal "VCC")
		(20 "In9.Cu" signal "VCC1")
		(22 "In10.Cu" signal "GND4")
		(24 "In11.Cu" signal "IN4")
		(26 "In12.Cu" signal "GND5")
		(28 "In13.Cu" signal "IN5")
		(30 "In14.Cu" signal "GND6")
		(32 "In15.Cu" signal "IN6")
		(34 "In16.Cu" signal "GND7")
		(2 "B.Cu" signal "BOTTOM")
		(9 "F.Adhes" user "F.Adhesive")
		(11 "B.Adhes" user "B.Adhesive")
		(13 "F.Paste" user "Package Geometry/Pastemask Top")
		(15 "B.Paste" user "Package Geometry/Pastemask Bottom")
		(5 "F.SilkS" user "Ref Des/Silkscreen Top")
		(7 "B.SilkS" user "Ref Des/Silkscreen Bottom")
		(1 "F.Mask" user "Board Geometry/Soldermask Top")
		(3 "B.Mask" user "Board Geometry/Soldermask Bottom")
		(17 "Dwgs.User" user "User.Drawings")
		(19 "Cmts.User" user "User.Comments")
		(21 "Eco1.User" user "User.Eco1")
		(23 "Eco2.User" user "User.Eco2")
		(25 "Edge.Cuts" user "Board Geometry/Outline")
		(27 "Margin" user)
		(31 "F.CrtYd" user "Package Geometry/Place Bound Top")
		(29 "B.CrtYd" user "Package Geometry/Place Bound Bottom")
		(35 "F.Fab" user "Ref Des/Assembly Top")
		(33 "B.Fab" user "Ref Des/Assembly Bottom")
	)
	(footprint ""
		(layer "F.Cu")
		(at 81.537302 -375.49963 -90)
		(property "Reference" "C732"
			(at 0 0 270)
			(layer "F.SilkS")
			(hide yes)
			(effects
				(font
					(size 1.27 1.27)
				)
			)
		)
		(property "Value" ""
			(at 0 0 270)
			(layer "F.Fab")
			(effects
				(font
					(size 1.27 1.27)
				)
			)
		)
		(duplicate_pad_numbers_are_jumpers no)
		(fp_line
			(start -0.299974 0.150114)
			(end -0.299974 -0.150114)
			(stroke
				(width 0.1)
				(type default)
			)
			(layer "F.Fab")
		)
		(fp_line
			(start 0.299974 0.150114)
			(end -0.299974 0.150114)
			(stroke
				(width 0.1)
				(type default)
			)
			(layer "F.Fab")
		)
		(fp_line
			(start -0.299974 -0.150114)
			(end 0.299974 -0.150114)
			(stroke
				(width 0.1)
				(type default)
			)
			(layer "F.Fab")
		)
		(fp_line
			(start 0.299974 -0.150114)
			(end 0.299974 0.150114)
			(stroke
				(width 0.1)
				(type default)
			)
			(layer "F.Fab")
		)
		(pad "1" smd rect
			(at -0.2667 0 270)
			(size 0.3048 0.381)
			(layers "F.Cu" "F.Mask" "F.Paste")
			(net "P5E_CPU1_P1_TX_C_DN<4>")
		)
		(pad "2" smd rect
			(at 0.2667 0 270)
			(size 0.3048 0.381)
			(layers "F.Cu" "F.Mask" "F.Paste")
			(net "P5E_CPU1_P1_TX_DN<4>")
		)
	)
	(footprint ""
		(layer "F.Cu")
		(at 335.818226 -339.625432 90)
		(property "Reference" "PR82"
			(at 0 0 90)
			(layer "F.SilkS")
			(hide yes)
			(effects
				(font
					(size 1.27 1.27)
				)
			)
		)
		(property "Value" ""
			(at 0 0 90)
			(layer "F.Fab")
			(effects
				(font
					(size 1.27 1.27)
				)
			)
		)
		(duplicate_pad_numbers_are_jumpers no)
		(fp_line
			(start 0.7874 -0.4064)
			(end 0.7874 0.4064)
			(stroke
				(width 0.1524)
				(type default)
			)
			(layer "F.SilkS")
		)
		(fp_line
			(start -0.7874 -0.4064)
			(end 0.7874 -0.4064)
			(stroke
				(width 0.1524)
				(type default)
			)
			(layer "F.SilkS")
		)
		(fp_line
			(start 0.7874 0.4064)
			(end -0.7874 0.4064)
			(stroke
				(width 0.1524)
				(type default)
			)
			(layer "F.SilkS")
		)
		(fp_line
			(start -0.7874 0.4064)
			(end -0.7874 -0.4064)
			(stroke
				(width 0.1524)
				(type default)
			)
			(layer "F.SilkS")
		)
		(fp_line
			(start -0.12065 -0.305054)
			(end -0.12065 -0.2794)
			(stroke
				(width 0.1)
				(type default)
			)
			(layer "F.Fab")
		)
		(fp_line
			(start -0.67945 -0.305054)
			(end -0.12065 -0.305054)
			(stroke
				(width 0.1)
				(type default)
			)
			(layer "F.Fab")
		)
		(fp_line
			(start 0.67945 -0.3048)
			(end 0.67945 0.3048)
			(stroke
				(width 0.1)
				(type default)
			)
			(layer "F.Fab")
		)
		(fp_line
			(start 0.12065 -0.3048)
			(end 0.67945 -0.3048)
			(stroke
				(width 0.1)
				(type default)
			)
			(layer "F.Fab")
		)
		(fp_line
			(start 0.12065 -0.2794)
			(end 0.12065 -0.3048)
			(stroke
				(width 0.1)
				(type default)
			)
			(layer "F.Fab")
		)
		(fp_line
			(start -0.12065 -0.2794)
			(end 0.12065 -0.2794)
			(stroke
				(width 0.1)
				(type default)
			)
			(layer "F.Fab")
		)
		(fp_line
			(start 0.120396 0.2794)
			(end -0.12065 0.2794)
			(stroke
				(width 0.1)
				(type default)
			)
			(layer "F.Fab")
		)
		(fp_line
			(start -0.12065 0.2794)
			(end -0.12065 0.3048)
			(stroke
				(width 0.1)
				(type default)
			)
			(layer "F.Fab")
		)
		(fp_line
			(start 0.67945 0.3048)
			(end 0.120396 0.3048)
			(stroke
				(width 0.1)
				(type default)
			)
			(layer "F.Fab")
		)
		(fp_line
			(start 0.120396 0.3048)
			(end 0.120396 0.2794)
			(stroke
				(width 0.1)
				(type default)
			)
			(layer "F.Fab")
		)
		(fp_line
			(start -0.12065 0.3048)
			(end -0.67945 0.3048)
			(stroke
				(width 0.1)
				(type default)
			)
			(layer "F.Fab")
		)
		(fp_line
			(start -0.67945 0.3048)
			(end -0.67945 -0.305054)
			(stroke
				(width 0.1)
				(type default)
			)
			(layer "F.Fab")
		)
		(pad "1" smd circle
			(at -0.40005 0 90)
			(size 0 0)
			(layers "F.Cu" "F.Mask" "F.Paste")
			(net "SW_PVDDCR_CPU1_P0_BOOT1")
		)
		(pad "2" smd circle
			(at 0.40005 0 90)
			(size 0 0)
			(layers "F.Cu" "F.Mask" "F.Paste")
			(net "SW_PVDDCR_CPU1_P0_BOOT1_R")
		)
	)
	(footprint ""
		(layer "F.Cu")
		(at 293.038022 -52.02809)
		(property "Reference" "R422"
			(at 0 0 0)
			(layer "F.SilkS")
			(hide yes)
			(effects
				(font
					(size 1.27 1.27)
				)
			)
		)
		(property "Value" ""
			(at 0 0 0)
			(layer "F.Fab")
			(effects
				(font
					(size 1.27 1.27)
				)
			)
		)
		(duplicate_pad_numbers_are_jumpers no)
		(fp_line
			(start -0.7874 -0.4064)
			(end 0.7874 -0.4064)
			(stroke
				(width 0.1524)
				(type default)
			)
			(layer "F.SilkS")
		)
		(fp_line
			(start -0.7874 0.4064)
			(end -0.7874 -0.4064)
			(stroke
				(width 0.1524)
				(type default)
			)
			(layer "F.SilkS")
		)
		(fp_line
			(start 0.7874 -0.4064)
			(end 0.7874 0.4064)
			(stroke
				(width 0.1524)
				(type default)
			)
			(layer "F.SilkS")
		)
		(fp_line
			(start 0.7874 0.4064)
			(end -0.7874 0.4064)
			(stroke
				(width 0.1524)
				(type default)
			)
			(layer "F.SilkS")
		)
		(fp_line
			(start -0.67945 -0.305054)
			(end -0.12065 -0.305054)
			(stroke
				(width 0.1)
				(type default)
			)
			(layer "F.Fab")
		)
		(fp_line
			(start -0.67945 0.3048)
			(end -0.67945 -0.305054)
			(stroke
				(width 0.1)
				(type default)
			)
			(layer "F.Fab")
		)
		(fp_line
			(start -0.12065 -0.305054)
			(end -0.12065 -0.2794)
			(stroke
				(width 0.1)
				(type default)
			)
			(layer "F.Fab")
		)
		(fp_line
			(start -0.12065 -0.2794)
			(end 0.12065 -0.2794)
			(stroke
				(width 0.1)
				(type default)
			)
			(layer "F.Fab")
		)
		(fp_line
			(start -0.12065 0.2794)
			(end -0.12065 0.3048)
			(stroke
				(width 0.1)
				(type default)
			)
			(layer "F.Fab")
		)
		(fp_line
			(start -0.12065 0.3048)
			(end -0.67945 0.3048)
			(stroke
				(width 0.1)
				(type default)
			)
			(layer "F.Fab")
		)
		(fp_line
			(start 0.120396 0.2794)
			(end -0.12065 0.2794)
			(stroke
				(width 0.1)
				(type default)
			)
			(layer "F.Fab")
		)
		(fp_line
			(start 0.120396 0.3048)
			(end 0.120396 0.2794)
			(stroke
				(width 0.1)
				(type default)
			)
			(layer "F.Fab")
		)
		(fp_line
			(start 0.12065 -0.3048)
			(end 0.67945 -0.3048)
			(stroke
				(width 0.1)
				(type default)
			)
			(layer "F.Fab")
		)
		(fp_line
			(start 0.12065 -0.2794)
			(end 0.12065 -0.3048)
			(stroke
				(width 0.1)
				(type default)
			)
			(layer "F.Fab")
		)
		(fp_line
			(start 0.67945 -0.3048)
			(end 0.67945 0.3048)
			(stroke
				(width 0.1)
				(type default)
			)
			(layer "F.Fab")
		)
		(fp_line
			(start 0.67945 0.3048)
			(end 0.120396 0.3048)
			(stroke
				(width 0.1)
				(type default)
			)
			(layer "F.Fab")
		)
		(pad "1" smd circle
			(at -0.40005 0)
			(size 0 0)
			(layers "F.Cu" "F.Mask" "F.Paste")
			(net "PVDD18_S5_P0")
		)
		(pad "2" smd circle
			(at 0.40005 0)
			(size 0 0)
			(layers "F.Cu" "F.Mask" "F.Paste")
			(net "RST_CPU0_SYS_N")
		)
	)
)
